# S9S_MB_2U (Grand Teton) — schematic netlist excerpt (pin names and nets, part order shuffled) for the footprints in the layout excerpt that follows; sources: Cadence DE-HDL packaged netlist, KiCad conversion of 03242023_DA0F0TMBIJ0_F0T_Motherboard_J_brd_V01_OCP.brd

R4304  Q_RES  22 1% CHIP  pkg 0402LF  page 179 : A = CLK_100M_E1S_0_R_DN ; B = CLK_100M_E1S_0_DN
R4454  Q_RES  0 5% EMPTY  pkg 0402LF  page 196 : A = USB2_HUB_2_EXT_DP ; B = USB2_HUB_2_BUF_EXT_R_DP
PC566  Q_CAPP  270UF 16V 20% OSCON  pkg THLF  page 259 : A = SW_P3V3_AUX_FLT ; B = GND

(kicad_pcb
	(version 20260206)
	(generator "pcbnew")
	(generator_version "10.0")
	(general
		(thickness 1.6)
		(legacy_teardrops no)
	)
	(paper "A4")
	(title_block
		(title "03242023_DA0F0TMBIJ0_F0T_Motherboard_J_brd_V01_OCP.brd")
		(comment 1 "Grand Teton / footprints 2319-2321 of 6105")
	)
	(layers
		(0 "F.Cu" signal "TOP")
		(4 "In1.Cu" signal "GND")
		(6 "In2.Cu" signal "IN1")
		(8 "In3.Cu" signal "GND1")
		(10 "In4.Cu" signal "IN2")
		(12 "In5.Cu" signal "GND2")
		(14 "In6.Cu" signal "IN3")
		(16 "In7.Cu" signal "GND3")
		(18 "In8.Cu" signal "VCC")
		(20 "In9.Cu" signal "VCC1")
		(22 "In10.Cu" signal "GND4")
		(24 "In11.Cu" signal "IN4")
		(26 "In12.Cu" signal "GND5")
		(28 "In13.Cu" signal "IN5")
		(30 "In14.Cu" signal "GND6")
		(32 "In15.Cu" signal "IN6")
		(34 "In16.Cu" signal "GND7")
		(2 "B.Cu" signal "BOTTOM")
		(9 "F.Adhes" user "F.Adhesive")
		(11 "B.Adhes" user "B.Adhesive")
		(13 "F.Paste" user "Package Geometry/Pastemask Top")
		(15 "B.Paste" user "Package Geometry/Pastemask Bottom")
		(5 "F.SilkS" user "Ref Des/Silkscreen Top")
		(7 "B.SilkS" user "Ref Des/Silkscreen Bottom")
		(1 "F.Mask" user "Board Geometry/Soldermask Top")
		(3 "B.Mask" user "Board Geometry/Soldermask Bottom")
		(17 "Dwgs.User" user "User.Drawings")
		(19 "Cmts.User" user "User.Comments")
		(21 "Eco1.User" user "User.Eco1")
		(23 "Eco2.User" user "User.Eco2")
		(25 "Edge.Cuts" user "Board Geometry/Outline")
		(27 "Margin" user)
		(31 "F.CrtYd" user "Package Geometry/Place Bound Top")
		(29 "B.CrtYd" user "Package Geometry/Place Bound Bottom")
		(35 "F.Fab" user "Ref Des/Assembly Top")
		(33 "B.Fab" user "Ref Des/Assembly Bottom")
	)
	(footprint ""
		(layer "F.Cu")
		(at 329.524868 -73.509378 90)
		(property "Reference" "R4304"
			(at 0 0 90)
			(layer "F.SilkS")
			(hide yes)
			(effects
				(font
					(size 1.27 1.27)
				)
			)
		)
		(property "Value" ""
			(at 0 0 90)
			(layer "F.Fab")
			(effects
				(font
					(size 1.27 1.27)
				)
			)
		)
		(duplicate_pad_numbers_are_jumpers no)
		(fp_line
			(start 0.7874 -0.4064)
			(end 0.7874 0.4064)
			(stroke
				(width 0.1524)
				(type default)
			)
			(layer "F.SilkS")
		)
		(fp_line
			(start -0.7874 -0.4064)
			(end 0.7874 -0.4064)
			(stroke
				(width 0.1524)
				(type default)
			)
			(layer "F.SilkS")
		)
		(fp_line
			(start 0.7874 0.4064)
			(end -0.7874 0.4064)
			(stroke
				(width 0.1524)
				(type default)
			)
			(layer "F.SilkS")
		)
		(fp_line
			(start -0.7874 0.4064)
			(end -0.7874 -0.4064)
			(stroke
				(width 0.1524)
				(type default)
			)
			(layer "F.SilkS")
		)
		(fp_line
			(start -0.12065 -0.305054)
			(end -0.12065 -0.2794)
			(stroke
				(width 0.1)
				(type default)
			)
			(layer "F.Fab")
		)
		(fp_line
			(start -0.67945 -0.305054)
			(end -0.12065 -0.305054)
			(stroke
				(width 0.1)
				(type default)
			)
			(layer "F.Fab")
		)
		(fp_line
			(start 0.67945 -0.3048)
			(end 0.67945 0.3048)
			(stroke
				(width 0.1)
				(type default)
			)
			(layer "F.Fab")
		)
		(fp_line
			(start 0.12065 -0.3048)
			(end 0.67945 -0.3048)
			(stroke
				(width 0.1)
				(type default)
			)
			(layer "F.Fab")
		)
		(fp_line
			(start 0.12065 -0.2794)
			(end 0.12065 -0.3048)
			(stroke
				(width 0.1)
				(type default)
			)
			(layer "F.Fab")
		)
		(fp_line
			(start -0.12065 -0.2794)
			(end 0.12065 -0.2794)
			(stroke
				(width 0.1)
				(type default)
			)
			(layer "F.Fab")
		)
		(fp_line
			(start 0.120396 0.2794)
			(end -0.12065 0.2794)
			(stroke
				(width 0.1)
				(type default)
			)
			(layer "F.Fab")
		)
		(fp_line
			(start -0.12065 0.2794)
			(end -0.12065 0.3048)
			(stroke
				(width 0.1)
				(type default)
			)
			(layer "F.Fab")
		)
		(fp_line
			(start 0.67945 0.3048)
			(end 0.120396 0.3048)
			(stroke
				(width 0.1)
				(type default)
			)
			(layer "F.Fab")
		)
		(fp_line
			(start 0.120396 0.3048)
			(end 0.120396 0.2794)
			(stroke
				(width 0.1)
				(type default)
			)
			(layer "F.Fab")
		)
		(fp_line
			(start -0.12065 0.3048)
			(end -0.67945 0.3048)
			(stroke
				(width 0.1)
				(type default)
			)
			(layer "F.Fab")
		)
		(fp_line
			(start -0.67945 0.3048)
			(end -0.67945 -0.305054)
			(stroke
				(width 0.1)
				(type default)
			)
			(layer "F.Fab")
		)
		(pad "1" smd circle
			(at -0.40005 0 90)
			(size 0 0)
			(layers "F.Cu" "F.Mask" "F.Paste")
			(net "CLK_100M_E1S_0_R_DN")
		)
		(pad "2" smd circle
			(at 0.40005 0 90)
			(size 0 0)
			(layers "F.Cu" "F.Mask" "F.Paste")
			(net "CLK_100M_E1S_0_DN")
		)
	)
	(footprint ""
		(layer "F.Cu")
		(at 463.90687 -75.960224 90)
		(property "Reference" "PC566"
			(at 0 0 90)
			(layer "F.SilkS")
			(hide yes)
			(effects
				(font
					(size 1.27 1.27)
				)
			)
		)
		(property "Value" ""
			(at 0 0 90)
			(layer "F.Fab")
			(effects
				(font
					(size 1.27 1.27)
				)
			)
		)
		(duplicate_pad_numbers_are_jumpers no)
		(fp_line
			(start -3.400044 1.249934)
			(end 3.400044 1.249934)
			(stroke
				(width 0.1524)
				(type default)
			)
			(layer "F.SilkS")
		)
		(fp_circle
			(center 0 1.249934)
			(end 0 4.649978)
			(stroke
				(width 0.1524)
				(type default)
			)
			(fill no)
			(layer "F.SilkS")
		)
		(fp_poly
			(pts
				(arc
					(start -3.400044 1.249934)
					(mid 0 4.649978)
					(end 3.400044 1.249934)
				)
			)
			(stroke
				(width 0)
				(type default)
			)
			(fill yes)
			(layer "F.SilkS")
		)
		(fp_circle
			(center 0 1.249934)
			(end 0 4.649978)
			(stroke
				(width 0.1)
				(type default)
			)
			(fill no)
			(layer "F.Fab")
		)
		(pad "1" thru_hole rect
			(at 0 0 90)
			(size 1.524 1.524)
			(drill 1.016)
			(layers "*.Cu" "*.Mask")
			(remove_unused_layers no)
			(net "SW_P3V3_AUX_FLT")
			(clearance 0)
			(padstack
				(mode front_inner_back)
				(layer "Inner"
					(shape circle)
					(size 1.524 1.524)
					(clearance 0)
				)
				(layer "B.Cu"
					(shape rect)
					(size 1.524 1.524)
					(clearance 0)
				)
			)
		)
		(pad "2" thru_hole circle
			(at 0 2.500122 90)
			(size 1.524 1.524)
			(drill 1.016)
			(layers "*.Cu" "*.Mask")
			(remove_unused_layers no)
			(net "GND")
			(clearance 0)
		)
	)
	(footprint ""
		(layer "F.Cu")
		(at 155.634944 -44.64685 90)
		(property "Reference" "R4454"
			(at 0 0 90)
			(layer "F.SilkS")
			(hide yes)
			(effects
				(font
					(size 1.27 1.27)
				)
			)
		)
		(property "Value" ""
			(at 0 0 90)
			(layer "F.Fab")
			(effects
				(font
					(size 1.27 1.27)
				)
			)
		)
		(duplicate_pad_numbers_are_jumpers no)
		(fp_line
			(start 0.7874 -0.4064)
			(end 0.7874 0.4064)
			(stroke
				(width 0.1524)
				(type default)
			)
			(layer "F.SilkS")
		)
		(fp_line
			(start -0.7874 -0.4064)
			(end 0.7874 -0.4064)
			(stroke
				(width 0.1524)
				(type default)
			)
			(layer "F.SilkS")
		)
		(fp_line
			(start -0.12065 -0.305054)
			(end -0.12065 -0.2794)
			(stroke
				(width 0.1)
				(type default)
			)
			(layer "F.Fab")
		)
		(fp_line
			(start -0.67945 -0.305054)
			(end -0.12065 -0.305054)
			(stroke
				(width 0.1)
				(type default)
			)
			(layer "F.Fab")
		)
		(fp_line
			(start 0.67945 -0.3048)
			(end 0.67945 0.3048)
			(stroke
				(width 0.1)
				(type default)
			)
			(layer "F.Fab")
		)
		(fp_line
			(start 0.12065 -0.3048)
			(end 0.67945 -0.3048)
			(stroke
				(width 0.1)
				(type default)
			)
			(layer "F.Fab")
		)
		(fp_line
			(start 0.12065 -0.2794)
			(end 0.12065 -0.3048)
			(stroke
				(width 0.1)
				(type default)
			)
			(layer "F.Fab")
		)
		(fp_line
			(start -0.12065 -0.2794)
			(end 0.12065 -0.2794)
			(stroke
				(width 0.1)
				(type default)
			)
			(layer "F.Fab")
		)
		(fp_line
			(start 0.120396 0.2794)
			(end -0.12065 0.2794)
			(stroke
				(width 0.1)
				(type default)
			)
			(layer "F.Fab")
		)
		(fp_line
			(start -0.12065 0.2794)
			(end -0.12065 0.3048)
			(stroke
				(width 0.1)
				(type default)
			)
			(layer "F.Fab")
		)
		(fp_line
			(start 0.67945 0.3048)
			(end 0.120396 0.3048)
			(stroke
				(width 0.1)
				(type default)
			)
			(layer "F.Fab")
		)
		(fp_line
			(start 0.120396 0.3048)
			(end 0.120396 0.2794)
			(stroke
				(width 0.1)
				(type default)
			)
			(layer "F.Fab")
		)
		(fp_line
			(start -0.12065 0.3048)
			(end -0.67945 0.3048)
			(stroke
				(width 0.1)
				(type default)
			)
			(layer "F.Fab")
		)
		(fp_line
			(start -0.67945 0.3048)
			(end -0.67945 -0.305054)
			(stroke
				(width 0.1)
				(type default)
			)
			(layer "F.Fab")
		)
		(pad "1" smd rect
			(at -0.40005 0 270)
			(size 0.4572 0.508)
			(layers "F.Cu" "F.Mask" "F.Paste")
			(net "USB2_HUB_2_EXT_DP")
		)
		(pad "2" smd rect
			(at 0.40005 0 270)
			(size 0.4572 0.508)
			(layers "F.Cu" "F.Mask" "F.Paste")
			(net "USB2_HUB_2_BUF_EXT_R_DP")
		)
	)
)
